(kicad_pcb
	(version 20260206)
	(generator "pcbnew")
	(generator_version "10.0")
	(general
		(thickness 1.6)
		(legacy_teardrops no)
	)
	(paper "A4")
	(title_block
		(title "panther-plus-userver — 13130-1b_20150205.brd")
		(comment 1 "Honey Badger (Wiwynn) / footprint 894 of 1509 (DIMM1), pads 72-78 of 210")
	)
	(layers
		(0 "F.Cu" signal "TOP")
		(4 "In1.Cu" signal "L2")
		(6 "In2.Cu" signal "L3")
		(8 "In3.Cu" signal "L4")
		(10 "In4.Cu" signal "L5")
		(12 "In5.Cu" signal "L6")
		(14 "In6.Cu" signal "L7")
		(16 "In7.Cu" signal "L8")
		(18 "In8.Cu" signal "L9")
		(20 "In9.Cu" signal "L10")
		(22 "In10.Cu" signal "L11")
		(2 "B.Cu" signal "BOTTOM")
		(9 "F.Adhes" user "F.Adhesive")
		(11 "B.Adhes" user "B.Adhesive")
		(13 "F.Paste" user "Package Geometry/Pastemask Top")
		(15 "B.Paste" user "Package Geometry/Pastemask Bottom")
		(5 "F.SilkS" user "Ref Des/Silkscreen Top")
		(7 "B.SilkS" user "Ref Des/Silkscreen Bottom")
		(1 "F.Mask" user "Board Geometry/Soldermask Top")
		(3 "B.Mask" user "Board Geometry/Soldermask Bottom")
		(17 "Dwgs.User" user "User.Drawings")
		(19 "Cmts.User" user "User.Comments")
		(21 "Eco1.User" user "User.Eco1")
		(23 "Eco2.User" user "User.Eco2")
		(25 "Edge.Cuts" user "Board Geometry/Outline")
		(27 "Margin" user)
		(31 "F.CrtYd" user "Package Geometry/Place Bound Top")
		(29 "B.CrtYd" user "Package Geometry/Place Bound Bottom")
		(35 "F.Fab" user "Ref Des/Assembly Top")
		(33 "B.Fab" user "Ref Des/Assembly Bottom")
	)
	(footprint ""
		(layer "B.Cu")
		(at 158.500064 -66.699892 180)
		(property "Reference" "DIMM1"
			(at 0 0 0)
			(layer "B.SilkS")
			(hide yes)
			(effects
				(font
					(size 1.27 1.27)
				)
				(justify mirror)
			)
		)
		(property "Value" "DDR3-204P-142-COLAY-1-GP-U"
			(at 41.312338 -16.676878 180)
			(unlocked yes)
			(layer "B.Fab")
			(hide yes)
			(effects
				(font
					(size 1.016 1.016)
					(thickness 0.1524)
				)
				(justify mirror)
			)
		)
		(property "Device Type" "AS0A626-J8R6-7H-COLAY-1"
			(at 41.312338 -18.200878 180)
			(unlocked yes)
			(layer "B.Fab")
			(hide yes)
			(effects
				(font
					(size 1.016 1.016)
					(thickness 0.1524)
				)
				(justify mirror)
			)
		)
		(duplicate_pad_numbers_are_jumpers no)
		(pad "70" smd custom
			(at -10.94994 4.100068)
			(size 0.1143 0.1143)
			(layers "B.Cu" "B.Mask" "B.Paste")
			(net "GND")
			(options
				(clearance outline)
				(anchor circle)
			)
			(primitives
				(gr_poly
					(pts
						(xy 0 -0.9017) (xy -0.03175 -0.89916) (xy -0.0635 -0.889) (xy -0.09144 -0.87376) (xy -0.11684 -0.85344)
						(xy -0.13716 -0.82804) (xy -0.1524 -0.8001) (xy -0.16256 -0.76835) (xy -0.1651 -0.7366) (xy -0.1651 0.13462)
						(xy -0.17272 0.14224) (xy -0.19812 0.1778) (xy -0.2032 0.18796) (xy -0.20701 0.19685) (xy -0.21209 0.20701)
						(xy -0.2159 0.21717) (xy -0.21844 0.22733) (xy -0.22225 0.23876) (xy -0.22352 0.24892) (xy -0.22606 0.25908)
						(xy -0.22733 0.27051) (xy -0.22733 0.28067) (xy -0.2286 0.2921) (xy -0.22733 0.30353) (xy -0.22733 0.31369)
						(xy -0.22606 0.32512) (xy -0.22352 0.33528) (xy -0.22225 0.34544) (xy -0.21844 0.35687) (xy -0.2159 0.36703)
						(xy -0.21209 0.37719) (xy -0.20701 0.38735) (xy -0.2032 0.39624) (xy -0.19812 0.4064) (xy -0.17272 0.44196)
						(xy -0.1651 0.44958) (xy -0.1651 0.7366) (xy -0.16256 0.76835) (xy -0.1524 0.8001) (xy -0.13716 0.82804)
						(xy -0.11684 0.85344) (xy -0.09144 0.87376) (xy -0.0635 0.889) (xy -0.03175 0.89916) (xy 0 0.9017)
						(xy 0.03175 0.89916) (xy 0.0635 0.889) (xy 0.09144 0.87376) (xy 0.11684 0.85344) (xy 0.13716 0.82804)
						(xy 0.1524 0.8001) (xy 0.16256 0.76835) (xy 0.1651 0.7366) (xy 0.1651 0.44958) (xy 0.17272 0.44196)
						(xy 0.19812 0.4064) (xy 0.2032 0.39624) (xy 0.20701 0.38735) (xy 0.21209 0.37719) (xy 0.2159 0.36703)
						(xy 0.21844 0.35687) (xy 0.22225 0.34544) (xy 0.22352 0.33528) (xy 0.22606 0.32512) (xy 0.22733 0.31369)
						(xy 0.22733 0.30353) (xy 0.2286 0.2921) (xy 0.22733 0.28067) (xy 0.22733 0.27051) (xy 0.22606 0.25908)
						(xy 0.22352 0.24892) (xy 0.22225 0.23876) (xy 0.21844 0.22733) (xy 0.2159 0.21717) (xy 0.21209 0.20701)
						(xy 0.20701 0.19685) (xy 0.2032 0.18796) (xy 0.19812 0.1778) (xy 0.17272 0.14224) (xy 0.1651 0.13462)
						(xy 0.1651 -0.7366) (xy 0.16256 -0.76835) (xy 0.1524 -0.8001) (xy 0.13716 -0.82804) (xy 0.11684 -0.85344)
						(xy 0.09144 -0.87376) (xy 0.0635 -0.889) (xy 0.03175 -0.89916)
					)
					(width 0)
					(fill yes)
				)
			)
		)
		(pad "71" smd custom
			(at -10.649966 -4.100068)
			(size 0.1143 0.1143)
			(layers "B.Cu" "B.Mask" "B.Paste")
			(net "M_A_ECC1")
			(options
				(clearance outline)
				(anchor circle)
			)
			(primitives
				(gr_poly
					(pts
						(xy 0 -0.9017) (xy -0.03175 -0.89916) (xy -0.0635 -0.889) (xy -0.09144 -0.87376) (xy -0.11684 -0.85344)
						(xy -0.13716 -0.82804) (xy -0.1524 -0.8001) (xy -0.16256 -0.76835) (xy -0.1651 -0.7366) (xy -0.1651 -0.19685)
						(xy -0.17272 -0.18923) (xy -0.17907 -0.18034) (xy -0.18669 -0.17145) (xy -0.19177 -0.16256) (xy -0.19812 -0.15367)
						(xy -0.20828 -0.13335) (xy -0.21971 -0.10287) (xy -0.22225 -0.09271) (xy -0.22479 -0.08128) (xy -0.22606 -0.07112)
						(xy -0.2286 -0.05969) (xy -0.2286 -0.01651) (xy -0.22606 -0.00508) (xy -0.22479 0.00508) (xy -0.22225 0.01651)
						(xy -0.21971 0.02667) (xy -0.20828 0.05715) (xy -0.19812 0.07747) (xy -0.19177 0.08636) (xy -0.18669 0.09525)
						(xy -0.17907 0.10414) (xy -0.17272 0.11303) (xy -0.1651 0.12065) (xy -0.1651 0.7366) (xy -0.16256 0.76835)
						(xy -0.1524 0.8001) (xy -0.13716 0.82804) (xy -0.11684 0.85344) (xy -0.09144 0.87376) (xy -0.0635 0.889)
						(xy -0.03175 0.89916) (xy 0 0.9017) (xy 0.03175 0.89916) (xy 0.0635 0.889) (xy 0.09144 0.87376)
						(xy 0.11684 0.85344) (xy 0.13716 0.82804) (xy 0.1524 0.8001) (xy 0.16256 0.76835) (xy 0.1651 0.7366)
						(xy 0.1651 0.11938) (xy 0.17272 0.11176) (xy 0.19812 0.0762) (xy 0.2032 0.06604) (xy 0.20701 0.05715)
						(xy 0.21209 0.04699) (xy 0.2159 0.03683) (xy 0.21844 0.02667) (xy 0.22225 0.01524) (xy 0.22352 0.00508)
						(xy 0.22606 -0.00508) (xy 0.22733 -0.01651) (xy 0.22733 -0.02667) (xy 0.2286 -0.0381) (xy 0.22733 -0.04953)
						(xy 0.22733 -0.05969) (xy 0.22606 -0.07112) (xy 0.22352 -0.08128) (xy 0.22225 -0.09144) (xy 0.21844 -0.10287)
						(xy 0.2159 -0.11303) (xy 0.21209 -0.12319) (xy 0.20701 -0.13335) (xy 0.2032 -0.14224) (xy 0.19812 -0.1524)
						(xy 0.17272 -0.18796) (xy 0.1651 -0.19558) (xy 0.1651 -0.7366) (xy 0.16256 -0.76835) (xy 0.1524 -0.8001)
						(xy 0.13716 -0.82804) (xy 0.11684 -0.85344) (xy 0.09144 -0.87376) (xy 0.0635 -0.889) (xy 0.03175 -0.89916)
					)
					(width 0)
					(fill yes)
				)
			)
		)
		(pad "72" smd custom
			(at -10.349992 4.100068)
			(size 0.1143 0.1143)
			(layers "B.Cu" "B.Mask" "B.Paste")
			(net "M_A_ECC4")
			(options
				(clearance outline)
				(anchor circle)
			)
			(primitives
				(gr_poly
					(pts
						(xy 0 -0.9017) (xy -0.03175 -0.89916) (xy -0.0635 -0.889) (xy -0.09144 -0.87376) (xy -0.11684 -0.85344)
						(xy -0.13716 -0.82804) (xy -0.1524 -0.8001) (xy -0.16256 -0.76835) (xy -0.1651 -0.7366) (xy -0.1651 -0.11938)
						(xy -0.17272 -0.11176) (xy -0.19812 -0.0762) (xy -0.2032 -0.06604) (xy -0.20701 -0.05715) (xy -0.21209 -0.04699)
						(xy -0.2159 -0.03683) (xy -0.21844 -0.02667) (xy -0.22225 -0.01524) (xy -0.22352 -0.00508) (xy -0.22606 0.00508)
						(xy -0.22733 0.01651) (xy -0.22733 0.02667) (xy -0.2286 0.0381) (xy -0.22733 0.04953) (xy -0.22733 0.05969)
						(xy -0.22606 0.07112) (xy -0.22352 0.08128) (xy -0.22225 0.09144) (xy -0.21844 0.10287) (xy -0.2159 0.11303)
						(xy -0.21209 0.12319) (xy -0.20701 0.13335) (xy -0.2032 0.14224) (xy -0.19812 0.1524) (xy -0.17272 0.18796)
						(xy -0.1651 0.19558) (xy -0.1651 0.7366) (xy -0.16256 0.76835) (xy -0.1524 0.8001) (xy -0.13716 0.82804)
						(xy -0.11684 0.85344) (xy -0.09144 0.87376) (xy -0.0635 0.889) (xy -0.03175 0.89916) (xy 0 0.9017)
						(xy 0.03175 0.89916) (xy 0.0635 0.889) (xy 0.09144 0.87376) (xy 0.11684 0.85344) (xy 0.13716 0.82804)
						(xy 0.1524 0.8001) (xy 0.16256 0.76835) (xy 0.1651 0.7366) (xy 0.1651 0.19685) (xy 0.17272 0.18923)
						(xy 0.17907 0.18034) (xy 0.18669 0.17145) (xy 0.19177 0.16256) (xy 0.19812 0.15367) (xy 0.20828 0.13335)
						(xy 0.21971 0.10287) (xy 0.22225 0.09271) (xy 0.22479 0.08128) (xy 0.22606 0.07112) (xy 0.2286 0.05969)
						(xy 0.2286 0.01651) (xy 0.22606 0.00508) (xy 0.22479 -0.00508) (xy 0.22225 -0.01651) (xy 0.21971 -0.02667)
						(xy 0.20828 -0.05715) (xy 0.19812 -0.07747) (xy 0.19177 -0.08636) (xy 0.18669 -0.09525) (xy 0.17907 -0.10414)
						(xy 0.17272 -0.11303) (xy 0.1651 -0.12065) (xy 0.1651 -0.7366) (xy 0.16256 -0.76835) (xy 0.1524 -0.8001)
						(xy 0.13716 -0.82804) (xy 0.11684 -0.85344) (xy 0.09144 -0.87376) (xy 0.0635 -0.889) (xy 0.03175 -0.89916)
					)
					(width 0)
					(fill yes)
				)
			)
		)
		(pad "73" smd custom
			(at -7.649972 -4.100068)
			(size 0.1143 0.1143)
			(layers "B.Cu" "B.Mask" "B.Paste")
			(net "GND")
			(options
				(clearance outline)
				(anchor circle)
			)
			(primitives
				(gr_poly
					(pts
						(xy 0 -0.9017) (xy -0.03175 -0.89916) (xy -0.0635 -0.889) (xy -0.09144 -0.87376) (xy -0.11684 -0.85344)
						(xy -0.13716 -0.82804) (xy -0.1524 -0.8001) (xy -0.16256 -0.76835) (xy -0.1651 -0.7366) (xy -0.1651 -0.44958)
						(xy -0.17272 -0.44196) (xy -0.19812 -0.4064) (xy -0.2032 -0.39624) (xy -0.20701 -0.38735) (xy -0.21209 -0.37719)
						(xy -0.2159 -0.36703) (xy -0.21844 -0.35687) (xy -0.22225 -0.34544) (xy -0.22352 -0.33528) (xy -0.22606 -0.32512)
						(xy -0.22733 -0.31369) (xy -0.22733 -0.30353) (xy -0.2286 -0.2921) (xy -0.22733 -0.28067) (xy -0.22733 -0.27051)
						(xy -0.22606 -0.25908) (xy -0.22352 -0.24892) (xy -0.22225 -0.23876) (xy -0.21844 -0.22733) (xy -0.2159 -0.21717)
						(xy -0.21209 -0.20701) (xy -0.20701 -0.19685) (xy -0.2032 -0.18796) (xy -0.19812 -0.1778) (xy -0.17272 -0.14224)
						(xy -0.1651 -0.13462) (xy -0.1651 0.7366) (xy -0.16256 0.76835) (xy -0.1524 0.8001) (xy -0.13716 0.82804)
						(xy -0.11684 0.85344) (xy -0.09144 0.87376) (xy -0.0635 0.889) (xy -0.03175 0.89916) (xy 0 0.9017)
						(xy 0.03175 0.89916) (xy 0.0635 0.889) (xy 0.09144 0.87376) (xy 0.11684 0.85344) (xy 0.13716 0.82804)
						(xy 0.1524 0.8001) (xy 0.16256 0.76835) (xy 0.1651 0.7366) (xy 0.1651 -0.13462) (xy 0.17272 -0.14224)
						(xy 0.19812 -0.1778) (xy 0.2032 -0.18796) (xy 0.20701 -0.19685) (xy 0.21209 -0.20701) (xy 0.2159 -0.21717)
						(xy 0.21844 -0.22733) (xy 0.22225 -0.23876) (xy 0.22352 -0.24892) (xy 0.22606 -0.25908) (xy 0.22733 -0.27051)
						(xy 0.22733 -0.28067) (xy 0.2286 -0.2921) (xy 0.22733 -0.30353) (xy 0.22733 -0.31369) (xy 0.22606 -0.32512)
						(xy 0.22352 -0.33528) (xy 0.22225 -0.34544) (xy 0.21844 -0.35687) (xy 0.2159 -0.36703) (xy 0.21209 -0.37719)
						(xy 0.20701 -0.38735) (xy 0.2032 -0.39624) (xy 0.19812 -0.4064) (xy 0.17272 -0.44196) (xy 0.1651 -0.44958)
						(xy 0.1651 -0.7366) (xy 0.16256 -0.76835) (xy 0.1524 -0.8001) (xy 0.13716 -0.82804) (xy 0.11684 -0.85344)
						(xy 0.09144 -0.87376) (xy 0.0635 -0.889) (xy 0.03175 -0.89916)
					)
					(width 0)
					(fill yes)
				)
			)
		)
		(pad "74" smd custom
			(at -7.349998 4.100068)
			(size 0.1143 0.1143)
			(layers "B.Cu" "B.Mask" "B.Paste")
			(net "M_A_ECC5")
			(options
				(clearance outline)
				(anchor circle)
			)
			(primitives
				(gr_poly
					(pts
						(xy 0 -0.9017) (xy -0.03175 -0.89916) (xy -0.0635 -0.889) (xy -0.09144 -0.87376) (xy -0.11684 -0.85344)
						(xy -0.13716 -0.82804) (xy -0.1524 -0.8001) (xy -0.16256 -0.76835) (xy -0.1651 -0.7366) (xy -0.1651 0.13462)
						(xy -0.17272 0.14224) (xy -0.19812 0.1778) (xy -0.2032 0.18796) (xy -0.20701 0.19685) (xy -0.21209 0.20701)
						(xy -0.2159 0.21717) (xy -0.21844 0.22733) (xy -0.22225 0.23876) (xy -0.22352 0.24892) (xy -0.22606 0.25908)
						(xy -0.22733 0.27051) (xy -0.22733 0.28067) (xy -0.2286 0.2921) (xy -0.22733 0.30353) (xy -0.22733 0.31369)
						(xy -0.22606 0.32512) (xy -0.22352 0.33528) (xy -0.22225 0.34544) (xy -0.21844 0.35687) (xy -0.2159 0.36703)
						(xy -0.21209 0.37719) (xy -0.20701 0.38735) (xy -0.2032 0.39624) (xy -0.19812 0.4064) (xy -0.17272 0.44196)
						(xy -0.1651 0.44958) (xy -0.1651 0.7366) (xy -0.16256 0.76835) (xy -0.1524 0.8001) (xy -0.13716 0.82804)
						(xy -0.11684 0.85344) (xy -0.09144 0.87376) (xy -0.0635 0.889) (xy -0.03175 0.89916) (xy 0 0.9017)
						(xy 0.03175 0.89916) (xy 0.0635 0.889) (xy 0.09144 0.87376) (xy 0.11684 0.85344) (xy 0.13716 0.82804)
						(xy 0.1524 0.8001) (xy 0.16256 0.76835) (xy 0.1651 0.7366) (xy 0.1651 0.44958) (xy 0.17272 0.44196)
						(xy 0.19812 0.4064) (xy 0.2032 0.39624) (xy 0.20701 0.38735) (xy 0.21209 0.37719) (xy 0.2159 0.36703)
						(xy 0.21844 0.35687) (xy 0.22225 0.34544) (xy 0.22352 0.33528) (xy 0.22606 0.32512) (xy 0.22733 0.31369)
						(xy 0.22733 0.30353) (xy 0.2286 0.2921) (xy 0.22733 0.28067) (xy 0.22733 0.27051) (xy 0.22606 0.25908)
						(xy 0.22352 0.24892) (xy 0.22225 0.23876) (xy 0.21844 0.22733) (xy 0.2159 0.21717) (xy 0.21209 0.20701)
						(xy 0.20701 0.19685) (xy 0.2032 0.18796) (xy 0.19812 0.1778) (xy 0.17272 0.14224) (xy 0.1651 0.13462)
						(xy 0.1651 -0.7366) (xy 0.16256 -0.76835) (xy 0.1524 -0.8001) (xy 0.13716 -0.82804) (xy 0.11684 -0.85344)
						(xy 0.09144 -0.87376) (xy 0.0635 -0.889) (xy 0.03175 -0.89916)
					)
					(width 0)
					(fill yes)
				)
			)
		)
		(pad "75" smd custom
			(at -7.050024 -4.100068)
			(size 0.1143 0.1143)
			(layers "B.Cu" "B.Mask" "B.Paste")
			(net "M_A_DQS_DN8")
			(options
				(clearance outline)
				(anchor circle)
			)
			(primitives
				(gr_poly
					(pts
						(xy 0 -0.9017) (xy -0.03175 -0.89916) (xy -0.0635 -0.889) (xy -0.09144 -0.87376) (xy -0.11684 -0.85344)
						(xy -0.13716 -0.82804) (xy -0.1524 -0.8001) (xy -0.16256 -0.76835) (xy -0.1651 -0.7366) (xy -0.1651 -0.19685)
						(xy -0.17272 -0.18923) (xy -0.17907 -0.18034) (xy -0.18669 -0.17145) (xy -0.19177 -0.16256) (xy -0.19812 -0.15367)
						(xy -0.20828 -0.13335) (xy -0.21971 -0.10287) (xy -0.22225 -0.09271) (xy -0.22479 -0.08128) (xy -0.22606 -0.07112)
						(xy -0.2286 -0.05969) (xy -0.2286 -0.01651) (xy -0.22606 -0.00508) (xy -0.22479 0.00508) (xy -0.22225 0.01651)
						(xy -0.21971 0.02667) (xy -0.20828 0.05715) (xy -0.19812 0.07747) (xy -0.19177 0.08636) (xy -0.18669 0.09525)
						(xy -0.17907 0.10414) (xy -0.17272 0.11303) (xy -0.1651 0.12065) (xy -0.1651 0.7366) (xy -0.16256 0.76835)
						(xy -0.1524 0.8001) (xy -0.13716 0.82804) (xy -0.11684 0.85344) (xy -0.09144 0.87376) (xy -0.0635 0.889)
						(xy -0.03175 0.89916) (xy 0 0.9017) (xy 0.03175 0.89916) (xy 0.0635 0.889) (xy 0.09144 0.87376)
						(xy 0.11684 0.85344) (xy 0.13716 0.82804) (xy 0.1524 0.8001) (xy 0.16256 0.76835) (xy 0.1651 0.7366)
						(xy 0.1651 0.11938) (xy 0.17272 0.11176) (xy 0.19812 0.0762) (xy 0.2032 0.06604) (xy 0.20701 0.05715)
						(xy 0.21209 0.04699) (xy 0.2159 0.03683) (xy 0.21844 0.02667) (xy 0.22225 0.01524) (xy 0.22352 0.00508)
						(xy 0.22606 -0.00508) (xy 0.22733 -0.01651) (xy 0.22733 -0.02667) (xy 0.2286 -0.0381) (xy 0.22733 -0.04953)
						(xy 0.22733 -0.05969) (xy 0.22606 -0.07112) (xy 0.22352 -0.08128) (xy 0.22225 -0.09144) (xy 0.21844 -0.10287)
						(xy 0.2159 -0.11303) (xy 0.21209 -0.12319) (xy 0.20701 -0.13335) (xy 0.2032 -0.14224) (xy 0.19812 -0.1524)
						(xy 0.17272 -0.18796) (xy 0.1651 -0.19558) (xy 0.1651 -0.7366) (xy 0.16256 -0.76835) (xy 0.1524 -0.8001)
						(xy 0.13716 -0.82804) (xy 0.11684 -0.85344) (xy 0.09144 -0.87376) (xy 0.0635 -0.889) (xy 0.03175 -0.89916)
					)
					(width 0)
					(fill yes)
				)
			)
		)
		(pad "76" smd custom
			(at -6.75005 4.100068)
			(size 0.1143 0.1143)
			(layers "B.Cu" "B.Mask" "B.Paste")
			(net "GND")
			(options
				(clearance outline)
				(anchor circle)
			)
			(primitives
				(gr_poly
					(pts
						(xy 0 -0.9017) (xy -0.03175 -0.89916) (xy -0.0635 -0.889) (xy -0.09144 -0.87376) (xy -0.11684 -0.85344)
						(xy -0.13716 -0.82804) (xy -0.1524 -0.8001) (xy -0.16256 -0.76835) (xy -0.1651 -0.7366) (xy -0.1651 -0.11938)
						(xy -0.17272 -0.11176) (xy -0.19812 -0.0762) (xy -0.2032 -0.06604) (xy -0.20701 -0.05715) (xy -0.21209 -0.04699)
						(xy -0.2159 -0.03683) (xy -0.21844 -0.02667) (xy -0.22225 -0.01524) (xy -0.22352 -0.00508) (xy -0.22606 0.00508)
						(xy -0.22733 0.01651) (xy -0.22733 0.02667) (xy -0.2286 0.0381) (xy -0.22733 0.04953) (xy -0.22733 0.05969)
						(xy -0.22606 0.07112) (xy -0.22352 0.08128) (xy -0.22225 0.09144) (xy -0.21844 0.10287) (xy -0.2159 0.11303)
						(xy -0.21209 0.12319) (xy -0.20701 0.13335) (xy -0.2032 0.14224) (xy -0.19812 0.1524) (xy -0.17272 0.18796)
						(xy -0.1651 0.19558) (xy -0.1651 0.7366) (xy -0.16256 0.76835) (xy -0.1524 0.8001) (xy -0.13716 0.82804)
						(xy -0.11684 0.85344) (xy -0.09144 0.87376) (xy -0.0635 0.889) (xy -0.03175 0.89916) (xy 0 0.9017)
						(xy 0.03175 0.89916) (xy 0.0635 0.889) (xy 0.09144 0.87376) (xy 0.11684 0.85344) (xy 0.13716 0.82804)
						(xy 0.1524 0.8001) (xy 0.16256 0.76835) (xy 0.1651 0.7366) (xy 0.1651 0.19685) (xy 0.17272 0.18923)
						(xy 0.17907 0.18034) (xy 0.18669 0.17145) (xy 0.19177 0.16256) (xy 0.19812 0.15367) (xy 0.20828 0.13335)
						(xy 0.21971 0.10287) (xy 0.22225 0.09271) (xy 0.22479 0.08128) (xy 0.22606 0.07112) (xy 0.2286 0.05969)
						(xy 0.2286 0.01651) (xy 0.22606 0.00508) (xy 0.22479 -0.00508) (xy 0.22225 -0.01651) (xy 0.21971 -0.02667)
						(xy 0.20828 -0.05715) (xy 0.19812 -0.07747) (xy 0.19177 -0.08636) (xy 0.18669 -0.09525) (xy 0.17907 -0.10414)
						(xy 0.17272 -0.11303) (xy 0.1651 -0.12065) (xy 0.1651 -0.7366) (xy 0.16256 -0.76835) (xy 0.1524 -0.8001)
						(xy 0.13716 -0.82804) (xy 0.11684 -0.85344) (xy 0.09144 -0.87376) (xy 0.0635 -0.889) (xy 0.03175 -0.89916)
					)
					(width 0)
					(fill yes)
				)
			)
		)
	)
)
